(kicad_pcb
	(version 20260206)
	(generator "pcbnew")
	(generator_version "10.0")
	(general
		(thickness 1.6)
		(legacy_teardrops no)
	)
	(paper "A4")
	(title_block
		(title "01162023_DA0F0TEBIF0_F0T_Expander_BD_F_brd_V02_OCP.brd")
		(comment 1 "Grand Teton / footprints 9425-9432 of 9728")
	)
	(layers
		(0 "F.Cu" signal "TOP")
		(4 "In1.Cu" signal "GND")
		(6 "In2.Cu" signal "VCC")
		(8 "In3.Cu" signal "VCC1")
		(10 "In4.Cu" signal "GND1")
		(12 "In5.Cu" signal "IN1")
		(14 "In6.Cu" signal "GND2")
		(16 "In7.Cu" signal "IN2")
		(18 "In8.Cu" signal "GND3")
		(20 "In9.Cu" signal "IN3")
		(22 "In10.Cu" signal "GND4")
		(24 "In11.Cu" signal "IN4")
		(26 "In12.Cu" signal "GND5")
		(28 "In13.Cu" signal "IN5")
		(30 "In14.Cu" signal "GND6")
		(32 "In15.Cu" signal "IN6")
		(34 "In16.Cu" signal "GND7")
		(2 "B.Cu" signal "BOTTOM")
		(9 "F.Adhes" user "F.Adhesive")
		(11 "B.Adhes" user "B.Adhesive")
		(13 "F.Paste" user "Package Geometry/Pastemask Top")
		(15 "B.Paste" user "Package Geometry/Pastemask Bottom")
		(5 "F.SilkS" user "Ref Des/Silkscreen Top")
		(7 "B.SilkS" user "Ref Des/Silkscreen Bottom")
		(1 "F.Mask" user "Board Geometry/Soldermask Top")
		(3 "B.Mask" user "Board Geometry/Soldermask Bottom")
		(17 "Dwgs.User" user "User.Drawings")
		(19 "Cmts.User" user "User.Comments")
		(21 "Eco1.User" user "User.Eco1")
		(23 "Eco2.User" user "User.Eco2")
		(25 "Edge.Cuts" user "Board Geometry/Outline")
		(27 "Margin" user)
		(31 "F.CrtYd" user "Package Geometry/Place Bound Top")
		(29 "B.CrtYd" user "Package Geometry/Place Bound Bottom")
		(35 "F.Fab" user "Ref Des/Assembly Top")
		(33 "B.Fab" user "Ref Des/Assembly Bottom")
	)
	(footprint ""
		(layer "B.Cu")
		(at 255.374902 -228.346 90)
		(property "Reference" "R3480"
			(at 0 0 90)
			(layer "B.SilkS")
			(hide yes)
			(effects
				(font
					(size 1.27 1.27)
				)
				(justify mirror)
			)
		)
		(property "Value" ""
			(at 0 0 90)
			(layer "B.Fab")
			(effects
				(font
					(size 1.27 1.27)
				)
				(justify mirror)
			)
		)
		(duplicate_pad_numbers_are_jumpers no)
		(fp_line
			(start 0.7874 -0.4064)
			(end -0.7874 -0.4064)
			(stroke
				(width 0.1524)
				(type default)
			)
			(layer "B.SilkS")
		)
		(fp_line
			(start -0.7874 -0.4064)
			(end -0.7874 0.4064)
			(stroke
				(width 0.1524)
				(type default)
			)
			(layer "B.SilkS")
		)
		(fp_line
			(start 0.7874 0.4064)
			(end 0.7874 -0.4064)
			(stroke
				(width 0.1524)
				(type default)
			)
			(layer "B.SilkS")
		)
		(fp_line
			(start -0.7874 0.4064)
			(end 0.7874 0.4064)
			(stroke
				(width 0.1524)
				(type default)
			)
			(layer "B.SilkS")
		)
		(fp_line
			(start 0.67945 -0.305054)
			(end 0.12065 -0.305054)
			(stroke
				(width 0.1)
				(type default)
			)
			(layer "B.Fab")
		)
		(fp_line
			(start 0.12065 -0.305054)
			(end 0.12065 -0.2794)
			(stroke
				(width 0.1)
				(type default)
			)
			(layer "B.Fab")
		)
		(fp_line
			(start -0.12065 -0.3048)
			(end -0.67945 -0.3048)
			(stroke
				(width 0.1)
				(type default)
			)
			(layer "B.Fab")
		)
		(fp_line
			(start -0.67945 -0.3048)
			(end -0.67945 0.3048)
			(stroke
				(width 0.1)
				(type default)
			)
			(layer "B.Fab")
		)
		(fp_line
			(start 0.12065 -0.2794)
			(end -0.12065 -0.2794)
			(stroke
				(width 0.1)
				(type default)
			)
			(layer "B.Fab")
		)
		(fp_line
			(start -0.12065 -0.2794)
			(end -0.12065 -0.3048)
			(stroke
				(width 0.1)
				(type default)
			)
			(layer "B.Fab")
		)
		(fp_line
			(start 0.12065 0.2794)
			(end 0.12065 0.3048)
			(stroke
				(width 0.1)
				(type default)
			)
			(layer "B.Fab")
		)
		(fp_line
			(start -0.120396 0.2794)
			(end 0.12065 0.2794)
			(stroke
				(width 0.1)
				(type default)
			)
			(layer "B.Fab")
		)
		(fp_line
			(start 0.67945 0.3048)
			(end 0.67945 -0.305054)
			(stroke
				(width 0.1)
				(type default)
			)
			(layer "B.Fab")
		)
		(fp_line
			(start 0.12065 0.3048)
			(end 0.67945 0.3048)
			(stroke
				(width 0.1)
				(type default)
			)
			(layer "B.Fab")
		)
		(fp_line
			(start -0.120396 0.3048)
			(end -0.120396 0.2794)
			(stroke
				(width 0.1)
				(type default)
			)
			(layer "B.Fab")
		)
		(fp_line
			(start -0.67945 0.3048)
			(end -0.120396 0.3048)
			(stroke
				(width 0.1)
				(type default)
			)
			(layer "B.Fab")
		)
		(pad "1" smd circle
			(at 0.40005 0 270)
			(size 0 0)
			(layers "B.Cu" "B.Mask" "B.Paste")
			(net "SPI_PEX2_SDIO1_MUX_R")
		)
		(pad "2" smd circle
			(at -0.40005 0 270)
			(size 0 0)
			(layers "B.Cu" "B.Mask" "B.Paste")
			(net "SPI_PEX2_SDIO1_MUX")
		)
	)
	(footprint ""
		(layer "B.Cu")
		(at 117.95379 -260.39572 -90)
		(property "Reference" "PR90"
			(at 0 0 90)
			(layer "B.SilkS")
			(hide yes)
			(effects
				(font
					(size 1.27 1.27)
				)
				(justify mirror)
			)
		)
		(property "Value" ""
			(at 0 0 90)
			(layer "B.Fab")
			(effects
				(font
					(size 1.27 1.27)
				)
				(justify mirror)
			)
		)
		(duplicate_pad_numbers_are_jumpers no)
		(fp_line
			(start -0.7874 0.4064)
			(end 0.7874 0.4064)
			(stroke
				(width 0.1524)
				(type default)
			)
			(layer "B.SilkS")
		)
		(fp_line
			(start 0.7874 0.4064)
			(end 0.7874 -0.4064)
			(stroke
				(width 0.1524)
				(type default)
			)
			(layer "B.SilkS")
		)
		(fp_line
			(start -0.7874 -0.4064)
			(end -0.7874 0.4064)
			(stroke
				(width 0.1524)
				(type default)
			)
			(layer "B.SilkS")
		)
		(fp_line
			(start 0.7874 -0.4064)
			(end -0.7874 -0.4064)
			(stroke
				(width 0.1524)
				(type default)
			)
			(layer "B.SilkS")
		)
		(fp_line
			(start -0.67945 0.3048)
			(end -0.120396 0.3048)
			(stroke
				(width 0.1)
				(type default)
			)
			(layer "B.Fab")
		)
		(fp_line
			(start -0.120396 0.3048)
			(end -0.120396 0.2794)
			(stroke
				(width 0.1)
				(type default)
			)
			(layer "B.Fab")
		)
		(fp_line
			(start 0.12065 0.3048)
			(end 0.67945 0.3048)
			(stroke
				(width 0.1)
				(type default)
			)
			(layer "B.Fab")
		)
		(fp_line
			(start 0.67945 0.3048)
			(end 0.67945 -0.305054)
			(stroke
				(width 0.1)
				(type default)
			)
			(layer "B.Fab")
		)
		(fp_line
			(start -0.120396 0.2794)
			(end 0.12065 0.2794)
			(stroke
				(width 0.1)
				(type default)
			)
			(layer "B.Fab")
		)
		(fp_line
			(start 0.12065 0.2794)
			(end 0.12065 0.3048)
			(stroke
				(width 0.1)
				(type default)
			)
			(layer "B.Fab")
		)
		(fp_line
			(start -0.12065 -0.2794)
			(end -0.12065 -0.3048)
			(stroke
				(width 0.1)
				(type default)
			)
			(layer "B.Fab")
		)
		(fp_line
			(start 0.12065 -0.2794)
			(end -0.12065 -0.2794)
			(stroke
				(width 0.1)
				(type default)
			)
			(layer "B.Fab")
		)
		(fp_line
			(start -0.67945 -0.3048)
			(end -0.67945 0.3048)
			(stroke
				(width 0.1)
				(type default)
			)
			(layer "B.Fab")
		)
		(fp_line
			(start -0.12065 -0.3048)
			(end -0.67945 -0.3048)
			(stroke
				(width 0.1)
				(type default)
			)
			(layer "B.Fab")
		)
		(fp_line
			(start 0.12065 -0.305054)
			(end 0.12065 -0.2794)
			(stroke
				(width 0.1)
				(type default)
			)
			(layer "B.Fab")
		)
		(fp_line
			(start 0.67945 -0.305054)
			(end 0.12065 -0.305054)
			(stroke
				(width 0.1)
				(type default)
			)
			(layer "B.Fab")
		)
		(pad "1" smd circle
			(at 0.40005 0 90)
			(size 0 0)
			(layers "B.Cu" "B.Mask" "B.Paste")
			(net "P0V8_PEX1_TSEN_R")
		)
		(pad "2" smd circle
			(at -0.40005 0 90)
			(size 0 0)
			(layers "B.Cu" "B.Mask" "B.Paste")
			(net "P0V8_PEX1_TSEN")
		)
	)
	(footprint ""
		(layer "B.Cu")
		(at 54.36997 -305.399948 -90)
		(property "Reference" "C2973"
			(at 0 0 90)
			(layer "B.SilkS")
			(hide yes)
			(effects
				(font
					(size 1.27 1.27)
				)
				(justify mirror)
			)
		)
		(property "Value" ""
			(at 0 0 90)
			(layer "B.Fab")
			(effects
				(font
					(size 1.27 1.27)
				)
				(justify mirror)
			)
		)
		(duplicate_pad_numbers_are_jumpers no)
		(fp_line
			(start -0.299974 0.150114)
			(end 0.299974 0.150114)
			(stroke
				(width 0.1)
				(type default)
			)
			(layer "B.Fab")
		)
		(fp_line
			(start 0.299974 0.150114)
			(end 0.299974 -0.150114)
			(stroke
				(width 0.1)
				(type default)
			)
			(layer "B.Fab")
		)
		(fp_line
			(start -0.299974 -0.150114)
			(end -0.299974 0.150114)
			(stroke
				(width 0.1)
				(type default)
			)
			(layer "B.Fab")
		)
		(fp_line
			(start 0.299974 -0.150114)
			(end -0.299974 -0.150114)
			(stroke
				(width 0.1)
				(type default)
			)
			(layer "B.Fab")
		)
		(pad "1" smd rect
			(at 0.2667 0 90)
			(size 0.3048 0.381)
			(layers "B.Cu" "B.Mask" "B.Paste")
			(net "P1V25_SERDES_VDDPLL_PEX0")
		)
		(pad "2" smd rect
			(at -0.2667 0 90)
			(size 0.3048 0.381)
			(layers "B.Cu" "B.Mask" "B.Paste")
			(net "GND")
		)
	)
	(footprint ""
		(layer "B.Cu")
		(at 117.653054 -163.598098)
		(property "Reference" "R823"
			(at 0 0 0)
			(layer "B.SilkS")
			(hide yes)
			(effects
				(font
					(size 1.27 1.27)
				)
				(justify mirror)
			)
		)
		(property "Value" ""
			(at 0 0 0)
			(layer "B.Fab")
			(effects
				(font
					(size 1.27 1.27)
				)
				(justify mirror)
			)
		)
		(duplicate_pad_numbers_are_jumpers no)
		(fp_line
			(start -0.7874 -0.4064)
			(end -0.7874 0.4064)
			(stroke
				(width 0.1524)
				(type default)
			)
			(layer "B.SilkS")
		)
		(fp_line
			(start -0.7874 0.4064)
			(end 0.7874 0.4064)
			(stroke
				(width 0.1524)
				(type default)
			)
			(layer "B.SilkS")
		)
		(fp_line
			(start 0.7874 -0.4064)
			(end -0.7874 -0.4064)
			(stroke
				(width 0.1524)
				(type default)
			)
			(layer "B.SilkS")
		)
		(fp_line
			(start 0.7874 0.4064)
			(end 0.7874 -0.4064)
			(stroke
				(width 0.1524)
				(type default)
			)
			(layer "B.SilkS")
		)
		(fp_line
			(start -0.67945 -0.3048)
			(end -0.67945 0.3048)
			(stroke
				(width 0.1)
				(type default)
			)
			(layer "B.Fab")
		)
		(fp_line
			(start -0.67945 0.3048)
			(end -0.120396 0.3048)
			(stroke
				(width 0.1)
				(type default)
			)
			(layer "B.Fab")
		)
		(fp_line
			(start -0.12065 -0.3048)
			(end -0.67945 -0.3048)
			(stroke
				(width 0.1)
				(type default)
			)
			(layer "B.Fab")
		)
		(fp_line
			(start -0.12065 -0.2794)
			(end -0.12065 -0.3048)
			(stroke
				(width 0.1)
				(type default)
			)
			(layer "B.Fab")
		)
		(fp_line
			(start -0.120396 0.2794)
			(end 0.12065 0.2794)
			(stroke
				(width 0.1)
				(type default)
			)
			(layer "B.Fab")
		)
		(fp_line
			(start -0.120396 0.3048)
			(end -0.120396 0.2794)
			(stroke
				(width 0.1)
				(type default)
			)
			(layer "B.Fab")
		)
		(fp_line
			(start 0.12065 -0.305054)
			(end 0.12065 -0.2794)
			(stroke
				(width 0.1)
				(type default)
			)
			(layer "B.Fab")
		)
		(fp_line
			(start 0.12065 -0.2794)
			(end -0.12065 -0.2794)
			(stroke
				(width 0.1)
				(type default)
			)
			(layer "B.Fab")
		)
		(fp_line
			(start 0.12065 0.2794)
			(end 0.12065 0.3048)
			(stroke
				(width 0.1)
				(type default)
			)
			(layer "B.Fab")
		)
		(fp_line
			(start 0.12065 0.3048)
			(end 0.67945 0.3048)
			(stroke
				(width 0.1)
				(type default)
			)
			(layer "B.Fab")
		)
		(fp_line
			(start 0.67945 -0.305054)
			(end 0.12065 -0.305054)
			(stroke
				(width 0.1)
				(type default)
			)
			(layer "B.Fab")
		)
		(fp_line
			(start 0.67945 0.3048)
			(end 0.67945 -0.305054)
			(stroke
				(width 0.1)
				(type default)
			)
			(layer "B.Fab")
		)
		(pad "1" smd circle
			(at 0.40005 0 180)
			(size 0 0)
			(layers "B.Cu" "B.Mask" "B.Paste")
			(net "P3V3_AUX_VCC")
		)
		(pad "2" smd circle
			(at -0.40005 0 180)
			(size 0 0)
			(layers "B.Cu" "B.Mask" "B.Paste")
			(net "PWRGD_P3V3_AUX")
		)
	)
	(footprint ""
		(layer "B.Cu")
		(at 165.655244 -153.0096)
		(property "Reference" "R121"
			(at 0 0 0)
			(layer "B.SilkS")
			(hide yes)
			(effects
				(font
					(size 1.27 1.27)
				)
				(justify mirror)
			)
		)
		(property "Value" ""
			(at 0 0 0)
			(layer "B.Fab")
			(effects
				(font
					(size 1.27 1.27)
				)
				(justify mirror)
			)
		)
		(duplicate_pad_numbers_are_jumpers no)
		(fp_line
			(start -0.7874 -0.4064)
			(end -0.7874 0.4064)
			(stroke
				(width 0.1524)
				(type default)
			)
			(layer "B.SilkS")
		)
		(fp_line
			(start -0.7874 0.4064)
			(end 0.7874 0.4064)
			(stroke
				(width 0.1524)
				(type default)
			)
			(layer "B.SilkS")
		)
		(fp_line
			(start 0.7874 -0.4064)
			(end -0.7874 -0.4064)
			(stroke
				(width 0.1524)
				(type default)
			)
			(layer "B.SilkS")
		)
		(fp_line
			(start 0.7874 0.4064)
			(end 0.7874 -0.4064)
			(stroke
				(width 0.1524)
				(type default)
			)
			(layer "B.SilkS")
		)
		(fp_line
			(start -0.67945 -0.3048)
			(end -0.67945 0.3048)
			(stroke
				(width 0.1)
				(type default)
			)
			(layer "B.Fab")
		)
		(fp_line
			(start -0.67945 0.3048)
			(end -0.120396 0.3048)
			(stroke
				(width 0.1)
				(type default)
			)
			(layer "B.Fab")
		)
		(fp_line
			(start -0.12065 -0.3048)
			(end -0.67945 -0.3048)
			(stroke
				(width 0.1)
				(type default)
			)
			(layer "B.Fab")
		)
		(fp_line
			(start -0.12065 -0.2794)
			(end -0.12065 -0.3048)
			(stroke
				(width 0.1)
				(type default)
			)
			(layer "B.Fab")
		)
		(fp_line
			(start -0.120396 0.2794)
			(end 0.12065 0.2794)
			(stroke
				(width 0.1)
				(type default)
			)
			(layer "B.Fab")
		)
		(fp_line
			(start -0.120396 0.3048)
			(end -0.120396 0.2794)
			(stroke
				(width 0.1)
				(type default)
			)
			(layer "B.Fab")
		)
		(fp_line
			(start 0.12065 -0.305054)
			(end 0.12065 -0.2794)
			(stroke
				(width 0.1)
				(type default)
			)
			(layer "B.Fab")
		)
		(fp_line
			(start 0.12065 -0.2794)
			(end -0.12065 -0.2794)
			(stroke
				(width 0.1)
				(type default)
			)
			(layer "B.Fab")
		)
		(fp_line
			(start 0.12065 0.2794)
			(end 0.12065 0.3048)
			(stroke
				(width 0.1)
				(type default)
			)
			(layer "B.Fab")
		)
		(fp_line
			(start 0.12065 0.3048)
			(end 0.67945 0.3048)
			(stroke
				(width 0.1)
				(type default)
			)
			(layer "B.Fab")
		)
		(fp_line
			(start 0.67945 -0.305054)
			(end 0.12065 -0.305054)
			(stroke
				(width 0.1)
				(type default)
			)
			(layer "B.Fab")
		)
		(fp_line
			(start 0.67945 0.3048)
			(end 0.67945 -0.305054)
			(stroke
				(width 0.1)
				(type default)
			)
			(layer "B.Fab")
		)
		(pad "1" smd circle
			(at 0.40005 0 180)
			(size 0 0)
			(layers "B.Cu" "B.Mask" "B.Paste")
			(net "NCSI_NIC2_TXD1")
		)
		(pad "2" smd circle
			(at -0.40005 0 180)
			(size 0 0)
			(layers "B.Cu" "B.Mask" "B.Paste")
			(net "GND")
		)
	)
	(footprint ""
		(layer "B.Cu")
		(at 361.44327 -277.644352 180)
		(property "Reference" "PC6620"
			(at 0 0 0)
			(layer "B.SilkS")
			(hide yes)
			(effects
				(font
					(size 1.27 1.27)
				)
				(justify mirror)
			)
		)
		(property "Value" ""
			(at 0 0 0)
			(layer "B.Fab")
			(effects
				(font
					(size 1.27 1.27)
				)
				(justify mirror)
			)
		)
		(duplicate_pad_numbers_are_jumpers no)
		(fp_line
			(start 1.524 0.762)
			(end 1.524 -0.762)
			(stroke
				(width 0.1524)
				(type default)
			)
			(layer "B.SilkS")
		)
		(fp_line
			(start 1.524 -0.762)
			(end -1.524 -0.762)
			(stroke
				(width 0.1524)
				(type default)
			)
			(layer "B.SilkS")
		)
		(fp_line
			(start -1.524 0.762)
			(end 1.524 0.762)
			(stroke
				(width 0.1524)
				(type default)
			)
			(layer "B.SilkS")
		)
		(fp_line
			(start -1.524 -0.762)
			(end -1.524 0.762)
			(stroke
				(width 0.1524)
				(type default)
			)
			(layer "B.SilkS")
		)
		(fp_line
			(start 1.1049 0.724916)
			(end -1.1049 0.724916)
			(stroke
				(width 0.1)
				(type default)
			)
			(layer "B.Fab")
		)
		(fp_line
			(start 1.1049 -0.724916)
			(end 1.1049 0.724916)
			(stroke
				(width 0.1)
				(type default)
			)
			(layer "B.Fab")
		)
		(fp_line
			(start -1.1049 0.724916)
			(end -1.1049 -0.724916)
			(stroke
				(width 0.1)
				(type default)
			)
			(layer "B.Fab")
		)
		(fp_line
			(start -1.1049 -0.724916)
			(end 1.1049 -0.724916)
			(stroke
				(width 0.1)
				(type default)
			)
			(layer "B.Fab")
		)
		(pad "1" smd rect
			(at 0.889 0 180)
			(size 1.016 1.27)
			(layers "B.Cu" "B.Mask" "B.Paste")
			(net "SW_P12V_P0V8_PEX3_FLT")
		)
		(pad "2" smd rect
			(at -0.889 0 180)
			(size 1.016 1.27)
			(layers "B.Cu" "B.Mask" "B.Paste")
			(net "GND")
		)
	)
	(footprint ""
		(layer "B.Cu")
		(at 323.316346 -238.175038)
		(property "Reference" "Q124"
			(at 1.4478 -1.819148 0)
			(unlocked yes)
			(layer "B.SilkS")
			(effects
				(font
					(size 0.7874 0.5842)
					(thickness 0.1524)
				)
				(justify left mirror)
			)
		)
		(property "Value" ""
			(at 0 0 0)
			(layer "B.Fab")
			(effects
				(font
					(size 1.27 1.27)
				)
				(justify mirror)
			)
		)
		(duplicate_pad_numbers_are_jumpers no)
		(fp_line
			(start -1.335278 -1.100074)
			(end 1.335278 -1.100074)
			(stroke
				(width 0.1524)
				(type default)
			)
			(layer "B.SilkS")
		)
		(fp_line
			(start -1.335278 1.100074)
			(end -1.335278 -1.100074)
			(stroke
				(width 0.1524)
				(type default)
			)
			(layer "B.SilkS")
		)
		(fp_line
			(start 1.335278 -1.100074)
			(end 1.335278 1.100074)
			(stroke
				(width 0.1524)
				(type default)
			)
			(layer "B.SilkS")
		)
		(fp_line
			(start 1.335278 1.100074)
			(end -1.335278 1.100074)
			(stroke
				(width 0.1524)
				(type default)
			)
			(layer "B.SilkS")
		)
		(fp_line
			(start -0.674878 -1.100074)
			(end 0.674878 -1.100074)
			(stroke
				(width 0.1)
				(type default)
			)
			(layer "B.Fab")
		)
		(fp_line
			(start -0.674878 1.100074)
			(end -0.674878 -1.100074)
			(stroke
				(width 0.1)
				(type default)
			)
			(layer "B.Fab")
		)
		(fp_line
			(start 0.674878 -1.100074)
			(end 0.674878 1.100074)
			(stroke
				(width 0.1)
				(type default)
			)
			(layer "B.Fab")
		)
		(fp_line
			(start 0.674878 1.100074)
			(end -0.674878 1.100074)
			(stroke
				(width 0.1)
				(type default)
			)
			(layer "B.Fab")
		)
		(pad "D" smd rect
			(at -0.8001 0 270)
			(size 0.6096 0.8128)
			(layers "B.Cu" "B.Mask" "B.Paste")
			(net "PWRGD_P3V3_AUX_MUX_N")
		)
		(pad "G" smd rect
			(at 0.8001 -0.649986 270)
			(size 0.6096 0.8128)
			(layers "B.Cu" "B.Mask" "B.Paste")
			(net "PWRGD_P3V3_AUX_R")
		)
		(pad "S" smd rect
			(at 0.8001 0.649986 270)
			(size 0.6096 0.8128)
			(layers "B.Cu" "B.Mask" "B.Paste")
			(net "GND")
		)
	)
	(footprint ""
		(layer "B.Cu")
		(at 173.375066 -305.399948 -90)
		(property "Reference" "C3147"
			(at 0 0 90)
			(layer "B.SilkS")
			(hide yes)
			(effects
				(font
					(size 1.27 1.27)
				)
				(justify mirror)
			)
		)
		(property "Value" ""
			(at 0 0 90)
			(layer "B.Fab")
			(effects
				(font
					(size 1.27 1.27)
				)
				(justify mirror)
			)
		)
		(duplicate_pad_numbers_are_jumpers no)
		(fp_line
			(start -0.299974 0.150114)
			(end 0.299974 0.150114)
			(stroke
				(width 0.1)
				(type default)
			)
			(layer "B.Fab")
		)
		(fp_line
			(start 0.299974 0.150114)
			(end 0.299974 -0.150114)
			(stroke
				(width 0.1)
				(type default)
			)
			(layer "B.Fab")
		)
		(fp_line
			(start -0.299974 -0.150114)
			(end -0.299974 0.150114)
			(stroke
				(width 0.1)
				(type default)
			)
			(layer "B.Fab")
		)
		(fp_line
			(start 0.299974 -0.150114)
			(end -0.299974 -0.150114)
			(stroke
				(width 0.1)
				(type default)
			)
			(layer "B.Fab")
		)
		(pad "1" smd rect
			(at 0.2667 0 90)
			(size 0.3048 0.381)
			(layers "B.Cu" "B.Mask" "B.Paste")
			(net "P1V25_SERDES_VDDPLL_PEX1")
		)
		(pad "2" smd rect
			(at -0.2667 0 90)
			(size 0.3048 0.381)
			(layers "B.Cu" "B.Mask" "B.Paste")
			(net "GND")
		)
	)
)
